(kicad_pcb
	(version 20241229)
	(generator "pcbnew")
	(generator_version "9.0")
	(general
		(thickness 1.294)
		(legacy_teardrops no)
	)
	(paper "A3")
	(title_block
		(title "Kintex 410T devboard")
		(date "2024-04-03")
		(rev "1.1.2")
		(comment 9 "footprints 451-451 of 975")
	)
	(layers
		(0 "F.Cu" mixed)
		(4 "In1.Cu" power)
		(6 "In2.Cu" power)
		(8 "In3.Cu" mixed)
		(10 "In4.Cu" power)
		(12 "In5.Cu" mixed)
		(14 "In6.Cu" power)
		(16 "In7.Cu" mixed)
		(18 "In8.Cu" power)
		(2 "B.Cu" mixed)
		(9 "F.Adhes" user "F.Adhesive")
		(11 "B.Adhes" user "B.Adhesive")
		(13 "F.Paste" user)
		(15 "B.Paste" user)
		(5 "F.SilkS" user "F.Silkscreen")
		(7 "B.SilkS" user "B.Silkscreen")
		(1 "F.Mask" user)
		(3 "B.Mask" user)
		(17 "Dwgs.User" user "User.Drawings")
		(19 "Cmts.User" user "User.Comments")
		(21 "Eco1.User" user "User.Eco1")
		(23 "Eco2.User" user "User.Eco2")
		(25 "Edge.Cuts" user)
		(27 "Margin" user)
		(31 "F.CrtYd" user "F.Courtyard")
		(29 "B.CrtYd" user "B.Courtyard")
		(35 "F.Fab" user)
		(33 "B.Fab" user)
	)
	(footprint "antmicro-footprints:Conn_Socket_Samtec_ERF5_2x20_ERF5-020-05.0-L-DV-K-TR"
		(locked yes)
		(layer "F.Cu")
		(at 249.9 125.8)
		(property "Reference" "J21"
			(at 6.46 -2.66 0)
			(layer "F.SilkS")
			(effects
				(font
					(size 0.7 0.7)
					(thickness 0.15)
				)
				(justify left bottom)
			)
		)
		(property "Value" "Socket_Samtec_ERF5_2x20_ERF5-020-05.0-L-DV-K-TR"
			(at 0 3.9 0)
			(layer "F.Fab")
			(effects
				(font
					(size 0.7 0.7)
					(thickness 0.15)
				)
				(justify left bottom)
			)
		)
		(property "Description" "Board to Board & Mezzanine Connectors 0.50 mm Edge Rate Rugged High Speed Socket"
			(at 0 0 0)
			(layer "F.Fab")
			(hide yes)
			(effects
				(font
					(size 1.27 1.27)
					(thickness 0.15)
				)
			)
		)
		(property "Author" "Antmicro"
			(at 0 0 0)
			(layer "F.Fab")
			(hide yes)
			(effects
				(font
					(size 1 1)
					(thickness 0.15)
				)
			)
		)
		(property "License" "Apache-2.0"
			(at 0 0 0)
			(layer "F.Fab")
			(hide yes)
			(effects
				(font
					(size 1 1)
					(thickness 0.15)
				)
			)
		)
		(property "MPN" "ERF5-020-05.0-L-DV-K-TR"
			(at 0 0 0)
			(layer "F.Fab")
			(hide yes)
			(effects
				(font
					(size 1 1)
					(thickness 0.15)
				)
			)
		)
		(property "Manufacturer" "Samtec"
			(at 0 0 0)
			(layer "F.Fab")
			(hide yes)
			(effects
				(font
					(size 1 1)
					(thickness 0.15)
				)
			)
		)
		(property "Pitch" "0.5 mm"
			(at 0 0 0)
			(layer "F.Fab")
			(hide yes)
			(effects
				(font
					(size 1 1)
					(thickness 0.15)
				)
			)
		)
		(sheetname "Supervisior MCU")
		(sheetfile "supervisor-mcu.kicad_sch")
		(attr smd)
		(fp_line
			(start -8.4 -2.475)
			(end -5.349 -2.475)
			(stroke
				(width 0.15)
				(type solid)
			)
			(layer "F.SilkS")
		)
		(fp_line
			(start -8.4 2.476)
			(end -8.4 -2.475)
			(stroke
				(width 0.15)
				(type solid)
			)
			(layer "F.SilkS")
		)
		(fp_line
			(start -5.349 2.476)
			(end -8.4 2.476)
			(stroke
				(width 0.15)
				(type solid)
			)
			(layer "F.SilkS")
		)
		(fp_line
			(start 5.351 -2.475)
			(end 8.401 -2.475)
			(stroke
				(width 0.15)
				(type solid)
			)
			(layer "F.SilkS")
		)
		(fp_line
			(start 8.401 -2.475)
			(end 8.401 2.476)
			(stroke
				(width 0.15)
				(type solid)
			)
			(layer "F.SilkS")
		)
		(fp_line
			(start 8.401 2.476)
			(end 5.351 2.476)
			(stroke
				(width 0.15)
				(type solid)
			)
			(layer "F.SilkS")
		)
		(fp_circle
			(center -5.2 2.9)
			(end -5.25 2.9)
			(stroke
				(width 0.15)
				(type solid)
			)
			(fill no)
			(layer "F.SilkS")
		)
		(fp_poly
			(pts
				(xy -4.623 -1.225) (xy -4.876 -1.225) (xy -4.876 -2.725) (xy -4.623 -2.725)
			)
			(stroke
				(width 0.01)
				(type solid)
			)
			(fill yes)
			(layer "F.Paste")
		)
		(fp_poly
			(pts
				(xy -4.623 2.726) (xy -4.876 2.726) (xy -4.876 1.226) (xy -4.623 1.226)
			)
			(stroke
				(width 0.01)
				(type solid)
			)
			(fill yes)
			(layer "F.Paste")
		)
		(fp_poly
			(pts
				(xy -4.123 -1.225) (xy -4.376 -1.225) (xy -4.376 -2.725) (xy -4.123 -2.725)
			)
			(stroke
				(width 0.01)
				(type solid)
			)
			(fill yes)
			(layer "F.Paste")
		)
		(fp_poly
			(pts
				(xy -4.123 2.726) (xy -4.376 2.726) (xy -4.376 1.226) (xy -4.123 1.226)
			)
			(stroke
				(width 0.01)
				(type solid)
			)
			(fill yes)
			(layer "F.Paste")
		)
		(fp_poly
			(pts
				(xy -3.623 -1.225) (xy -3.875 -1.225) (xy -3.875 -2.725) (xy -3.623 -2.725)
			)
			(stroke
				(width 0.01)
				(type solid)
			)
			(fill yes)
			(layer "F.Paste")
		)
		(fp_poly
			(pts
				(xy -3.623 2.726) (xy -3.875 2.726) (xy -3.875 1.226) (xy -3.623 1.226)
			)
			(stroke
				(width 0.01)
				(type solid)
			)
			(fill yes)
			(layer "F.Paste")
		)
		(fp_poly
			(pts
				(xy -3.123 -1.225) (xy -3.375 -1.225) (xy -3.375 -2.725) (xy -3.123 -2.725)
			)
			(stroke
				(width 0.01)
				(type solid)
			)
			(fill yes)
			(layer "F.Paste")
		)
		(fp_poly
			(pts
				(xy -3.123 2.726) (xy -3.375 2.726) (xy -3.375 1.226) (xy -3.123 1.226)
			)
			(stroke
				(width 0.01)
				(type solid)
			)
			(fill yes)
			(layer "F.Paste")
		)
		(fp_poly
			(pts
				(xy -2.623 -1.225) (xy -2.875 -1.225) (xy -2.875 -2.725) (xy -2.623 -2.725)
			)
			(stroke
				(width 0.01)
				(type solid)
			)
			(fill yes)
			(layer "F.Paste")
		)
		(fp_poly
			(pts
				(xy -2.623 2.726) (xy -2.875 2.726) (xy -2.875 1.226) (xy -2.623 1.226)
			)
			(stroke
				(width 0.01)
				(type solid)
			)
			(fill yes)
			(layer "F.Paste")
		)
		(fp_poly
			(pts
				(xy -2.123 -1.225) (xy -2.375 -1.225) (xy -2.375 -2.725) (xy -2.123 -2.725)
			)
			(stroke
				(width 0.01)
				(type solid)
			)
			(fill yes)
			(layer "F.Paste")
		)
		(fp_poly
			(pts
				(xy -2.123 2.726) (xy -2.375 2.726) (xy -2.375 1.226) (xy -2.123 1.226)
			)
			(stroke
				(width 0.01)
				(type solid)
			)
			(fill yes)
			(layer "F.Paste")
		)
		(fp_poly
			(pts
				(xy -1.622 -1.225) (xy -1.876 -1.225) (xy -1.876 -2.725) (xy -1.622 -2.725)
			)
			(stroke
				(width 0.01)
				(type solid)
			)
			(fill yes)
			(layer "F.Paste")
		)
		(fp_poly
			(pts
				(xy -1.622 2.726) (xy -1.876 2.726) (xy -1.876 1.226) (xy -1.622 1.226)
			)
			(stroke
				(width 0.01)
				(type solid)
			)
			(fill yes)
			(layer "F.Paste")
		)
		(fp_poly
			(pts
				(xy -1.122 -1.225) (xy -1.376 -1.225) (xy -1.376 -2.725) (xy -1.122 -2.725)
			)
			(stroke
				(width 0.01)
				(type solid)
			)
			(fill yes)
			(layer "F.Paste")
		)
		(fp_poly
			(pts
				(xy -1.122 2.726) (xy -1.376 2.726) (xy -1.376 1.226) (xy -1.122 1.226)
			)
			(stroke
				(width 0.01)
				(type solid)
			)
			(fill yes)
			(layer "F.Paste")
		)
		(fp_poly
			(pts
				(xy -0.621 -1.225) (xy -0.875 -1.225) (xy -0.875 -2.725) (xy -0.621 -2.725)
			)
			(stroke
				(width 0.01)
				(type solid)
			)
			(fill yes)
			(layer "F.Paste")
		)
		(fp_poly
			(pts
				(xy -0.621 2.726) (xy -0.875 2.726) (xy -0.875 1.226) (xy -0.621 1.226)
			)
			(stroke
				(width 0.01)
				(type solid)
			)
			(fill yes)
			(layer "F.Paste")
		)
		(fp_poly
			(pts
				(xy -0.121 -1.225) (xy -0.375 -1.225) (xy -0.375 -2.725) (xy -0.121 -2.725)
			)
			(stroke
				(width 0.01)
				(type solid)
			)
			(fill yes)
			(layer "F.Paste")
		)
		(fp_poly
			(pts
				(xy -0.121 2.726) (xy -0.375 2.726) (xy -0.375 1.226) (xy -0.121 1.226)
			)
			(stroke
				(width 0.01)
				(type solid)
			)
			(fill yes)
			(layer "F.Paste")
		)
		(fp_poly
			(pts
				(xy 0.377 -1.225) (xy 0.123 -1.225) (xy 0.123 -2.725) (xy 0.377 -2.725)
			)
			(stroke
				(width 0.01)
				(type solid)
			)
			(fill yes)
			(layer "F.Paste")
		)
		(fp_poly
			(pts
				(xy 0.377 2.726) (xy 0.123 2.726) (xy 0.123 1.226) (xy 0.377 1.226)
			)
			(stroke
				(width 0.01)
				(type solid)
			)
			(fill yes)
			(layer "F.Paste")
		)
		(fp_poly
			(pts
				(xy 0.877 -1.225) (xy 0.623 -1.225) (xy 0.623 -2.725) (xy 0.877 -2.725)
			)
			(stroke
				(width 0.01)
				(type solid)
			)
			(fill yes)
			(layer "F.Paste")
		)
		(fp_poly
			(pts
				(xy 0.877 2.726) (xy 0.623 2.726) (xy 0.623 1.226) (xy 0.877 1.226)
			)
			(stroke
				(width 0.01)
				(type solid)
			)
			(fill yes)
			(layer "F.Paste")
		)
		(fp_poly
			(pts
				(xy 1.377 -1.225) (xy 1.123 -1.225) (xy 1.123 -2.725) (xy 1.377 -2.725)
			)
			(stroke
				(width 0.01)
				(type solid)
			)
			(fill yes)
			(layer "F.Paste")
		)
		(fp_poly
			(pts
				(xy 1.377 2.726) (xy 1.123 2.726) (xy 1.123 1.226) (xy 1.377 1.226)
			)
			(stroke
				(width 0.01)
				(type solid)
			)
			(fill yes)
			(layer "F.Paste")
		)
		(fp_poly
			(pts
				(xy 1.877 -1.225) (xy 1.623 -1.225) (xy 1.623 -2.725) (xy 1.877 -2.725)
			)
			(stroke
				(width 0.01)
				(type solid)
			)
			(fill yes)
			(layer "F.Paste")
		)
		(fp_poly
			(pts
				(xy 1.877 2.726) (xy 1.623 2.726) (xy 1.623 1.226) (xy 1.877 1.226)
			)
			(stroke
				(width 0.01)
				(type solid)
			)
			(fill yes)
			(layer "F.Paste")
		)
		(fp_poly
			(pts
				(xy 2.378 -1.225) (xy 2.125 -1.225) (xy 2.125 -2.725) (xy 2.378 -2.725)
			)
			(stroke
				(width 0.01)
				(type solid)
			)
			(fill yes)
			(layer "F.Paste")
		)
		(fp_poly
			(pts
				(xy 2.378 2.726) (xy 2.125 2.726) (xy 2.125 1.226) (xy 2.378 1.226)
			)
			(stroke
				(width 0.01)
				(type solid)
			)
			(fill yes)
			(layer "F.Paste")
		)
		(fp_poly
			(pts
				(xy 2.878 -1.225) (xy 2.625 -1.225) (xy 2.625 -2.725) (xy 2.878 -2.725)
			)
			(stroke
				(width 0.01)
				(type solid)
			)
			(fill yes)
			(layer "F.Paste")
		)
		(fp_poly
			(pts
				(xy 2.878 2.726) (xy 2.625 2.726) (xy 2.625 1.226) (xy 2.878 1.226)
			)
			(stroke
				(width 0.01)
				(type solid)
			)
			(fill yes)
			(layer "F.Paste")
		)
		(fp_poly
			(pts
				(xy 3.378 -1.225) (xy 3.125 -1.225) (xy 3.125 -2.725) (xy 3.378 -2.725)
			)
			(stroke
				(width 0.01)
				(type solid)
			)
			(fill yes)
			(layer "F.Paste")
		)
		(fp_poly
			(pts
				(xy 3.378 2.726) (xy 3.125 2.726) (xy 3.125 1.226) (xy 3.378 1.226)
			)
			(stroke
				(width 0.01)
				(type solid)
			)
			(fill yes)
			(layer "F.Paste")
		)
		(fp_poly
			(pts
				(xy 3.878 -1.225) (xy 3.625 -1.225) (xy 3.625 -2.725) (xy 3.878 -2.725)
			)
			(stroke
				(width 0.01)
				(type solid)
			)
			(fill yes)
			(layer "F.Paste")
		)
		(fp_poly
			(pts
				(xy 3.878 2.726) (xy 3.625 2.726) (xy 3.625 1.226) (xy 3.878 1.226)
			)
			(stroke
				(width 0.01)
				(type solid)
			)
			(fill yes)
			(layer "F.Paste")
		)
		(fp_poly
			(pts
				(xy 4.377 -1.225) (xy 4.124 -1.225) (xy 4.124 -2.725) (xy 4.377 -2.725)
			)
			(stroke
				(width 0.01)
				(type solid)
			)
			(fill yes)
			(layer "F.Paste")
		)
		(fp_poly
			(pts
				(xy 4.377 2.726) (xy 4.124 2.726) (xy 4.124 1.226) (xy 4.377 1.226)
			)
			(stroke
				(width 0.01)
				(type solid)
			)
			(fill yes)
			(layer "F.Paste")
		)
		(fp_poly
			(pts
				(xy 4.877 -1.225) (xy 4.624 -1.225) (xy 4.624 -2.725) (xy 4.877 -2.725)
			)
			(stroke
				(width 0.01)
				(type solid)
			)
			(fill yes)
			(layer "F.Paste")
		)
		(fp_poly
			(pts
				(xy 4.877 2.726) (xy 4.624 2.726) (xy 4.624 1.226) (xy 4.877 1.226)
			)
			(stroke
				(width 0.01)
				(type solid)
			)
			(fill yes)
			(layer "F.Paste")
		)
		(fp_rect
			(start 8.651 2.926)
			(end -8.65 -2.925)
			(stroke
				(width 0.05)
				(type solid)
			)
			(fill no)
			(layer "F.CrtYd")
		)
		(fp_line
			(start -8.39 1.35)
			(end -7.27 2.47)
			(stroke
				(width 0.15)
				(type solid)
			)
			(layer "F.Fab")
		)
		(fp_rect
			(start 8.401 2.476)
			(end -8.4 -2.475)
			(stroke
				(width 0.15)
				(type solid)
			)
			(fill no)
			(layer "F.Fab")
		)
		(pad "" np_thru_hole circle
			(at -6.9 1.401 180)
			(size 1.45 1.45)
			(drill 1.45)
			(layers "*.Cu" "*.Mask")
		)
		(pad "" np_thru_hole circle
			(at 6.901 1.401 180)
			(size 1.45 1.45)
			(drill 1.45)
			(layers "*.Cu" "*.Mask")
		)
		(pad "1" smd rect
			(at -4.748 1.976 270)
			(size 1.5 0.3)
			(layers "F.Cu" "F.Mask")
			(net 1 "GND")
			(pintype "passive")
		)
		(pad "2" smd rect
			(at -4.748 -1.975 270)
			(size 1.5 0.3)
			(layers "F.Cu" "F.Mask")
			(net 1076 "/Supervisior MCU/USB_A15")
			(pintype "passive")
		)
		(pad "3" smd rect
			(at -4.248 1.976 270)
			(size 1.5 0.3)
			(layers "F.Cu" "F.Mask")
			(net 1 "GND")
			(pintype "passive")
		)
		(pad "4" smd rect
			(at -4.248 -1.975 270)
			(size 1.5 0.3)
			(layers "F.Cu" "F.Mask")
			(net 1078 "/Supervisior MCU/USB_A17")
			(pintype "passive")
		)
		(pad "5" smd rect
			(at -3.749 1.976 270)
			(size 1.5 0.3)
			(layers "F.Cu" "F.Mask")
			(net 1 "GND")
			(pintype "passive")
		)
		(pad "6" smd rect
			(at -3.749 -1.975 270)
			(size 1.5 0.3)
			(layers "F.Cu" "F.Mask")
			(net 1067 "/Supervisior MCU/USB_A6")
			(pintype "passive")
		)
		(pad "7" smd rect
			(at -3.249 1.976 270)
			(size 1.5 0.3)
			(layers "F.Cu" "F.Mask")
			(net 1 "GND")
			(pintype "passive")
		)
		(pad "8" smd rect
			(at -3.249 -1.975 270)
			(size 1.5 0.3)
			(layers "F.Cu" "F.Mask")
			(net 265 "/Supervisior MCU/PWR_ON")
			(pintype "passive")
		)
		(pad "9" smd rect
			(at -2.749 1.976 270)
			(size 1.5 0.3)
			(layers "F.Cu" "F.Mask")
			(net 1 "GND")
			(pintype "passive")
		)
		(pad "10" smd rect
			(at -2.749 -1.975 270)
			(size 1.5 0.3)
			(layers "F.Cu" "F.Mask")
			(net 1080 "/Supervisior MCU/USB_A19")
			(pintype "passive")
		)
		(pad "11" smd rect
			(at -2.249 1.976 270)
			(size 1.5 0.3)
			(layers "F.Cu" "F.Mask")
			(net 1061 "/Supervisior MCU/USB_A0")
			(pintype "passive")
		)
		(pad "12" smd rect
			(at -2.249 -1.975 270)
			(size 1.5 0.3)
			(layers "F.Cu" "F.Mask")
			(net 1075 "/Supervisior MCU/USB_A14")
			(pintype "passive")
		)
		(pad "13" smd rect
			(at -1.749 1.976 270)
			(size 1.5 0.3)
			(layers "F.Cu" "F.Mask")
			(net 1083 "/Supervisior MCU/RXD1")
			(pintype "passive")
		)
		(pad "14" smd rect
			(at -1.749 -1.975 270)
			(size 1.5 0.3)
			(layers "F.Cu" "F.Mask")
			(net 1118 "/Supervisior MCU/USB_CLK0")
			(pintype "passive")
		)
		(pad "15" smd rect
			(at -1.249 1.976 270)
			(size 1.5 0.3)
			(layers "F.Cu" "F.Mask")
			(net 1074 "/Supervisior MCU/USB_A13")
			(pintype "passive")
		)
		(pad "16" smd rect
			(at -1.249 -1.975 270)
			(size 1.5 0.3)
			(layers "F.Cu" "F.Mask")
			(net 111 "/Supervisior MCU/FAN_PWM")
			(pintype "passive")
		)
		(pad "17" smd rect
			(at -0.748 1.976 270)
			(size 1.5 0.3)
			(layers "F.Cu" "F.Mask")
			(net 1062 "/Supervisior MCU/USB_A1")
			(pintype "passive")
		)
		(pad "18" smd rect
			(at -0.748 -1.975 270)
			(size 1.5 0.3)
			(layers "F.Cu" "F.Mask")
			(net 1073 "/Supervisior MCU/USB_A12")
			(pintype "passive")
		)
		(pad "19" smd rect
			(at -0.248 1.976 270)
			(size 1.5 0.3)
			(layers "F.Cu" "F.Mask")
			(net 1068 "/Supervisior MCU/USB_A7")
			(pintype "passive")
		)
		(pad "20" smd rect
			(at -0.248 -1.975 270)
			(size 1.5 0.3)
			(layers "F.Cu" "F.Mask")
			(net 1072 "/Supervisior MCU/USB_A11")
			(pintype "passive")
		)
		(pad "21" smd rect
			(at 0.25 1.976 270)
			(size 1.5 0.3)
			(layers "F.Cu" "F.Mask")
			(net 1077 "/Supervisior MCU/USB_A16")
			(pintype "passive")
		)
		(pad "22" smd rect
			(at 0.25 -1.975 270)
			(size 1.5 0.3)
			(layers "F.Cu" "F.Mask")
			(net 1071 "/Supervisior MCU/USB_A10")
			(pintype "passive")
		)
		(pad "23" smd rect
			(at 0.75 1.976 270)
			(size 1.5 0.3)
			(layers "F.Cu" "F.Mask")
			(net 1079 "/Supervisior MCU/USB_A18")
			(pintype "passive")
		)
		(pad "24" smd rect
			(at 0.75 -1.975 270)
			(size 1.5 0.3)
			(layers "F.Cu" "F.Mask")
			(net 1082 "/Supervisior MCU/TXD0")
			(pintype "passive")
		)
		(pad "25" smd rect
			(at 1.25 1.976 270)
			(size 1.5 0.3)
			(layers "F.Cu" "F.Mask")
			(net 276 "/Supervisior MCU/SW_STATE")
			(pintype "passive")
		)
		(pad "26" smd rect
			(at 1.25 -1.975 270)
			(size 1.5 0.3)
			(layers "F.Cu" "F.Mask")
			(net 1081 "/Supervisior MCU/TXD1")
			(pintype "passive")
		)
		(pad "27" smd rect
			(at 1.75 1.976 270)
			(size 1.5 0.3)
			(layers "F.Cu" "F.Mask")
			(net 112 "/Supervisior MCU/SAM_FPGA_CCLK")
			(pintype "passive")
		)
		(pad "28" smd rect
			(at 1.75 -1.975 270)
			(size 1.5 0.3)
			(layers "F.Cu" "F.Mask")
			(net 1084 "/Supervisior MCU/RXD0")
			(pintype "passive")
		)
		(pad "29" smd rect
			(at 2.25 1.976 270)
			(size 1.5 0.3)
			(layers "F.Cu" "F.Mask")
			(net 1108 "/Supervisior MCU/PWR_RST")
			(pintype "passive")
		)
		(pad "30" smd rect
			(at 2.25 -1.975 270)
			(size 1.5 0.3)
			(layers "F.Cu" "F.Mask")
			(net 1087 "/Supervisior MCU/PGOOD_1V8")
			(pintype "passive")
		)
		(pad "31" smd rect
			(at 2.75 1.976 270)
			(size 1.5 0.3)
			(layers "F.Cu" "F.Mask")
			(net 1063 "/Supervisior MCU/USB_A2")
			(pintype "passive")
		)
		(pad "32" smd rect
			(at 2.75 -1.975 270)
			(size 1.5 0.3)
			(layers "F.Cu" "F.Mask")
			(net 703 "+5V")
			(pintype "passive")
		)
		(pad "33" smd rect
			(at 3.25 1.976 270)
			(size 1.5 0.3)
			(layers "F.Cu" "F.Mask")
			(net 1066 "/Supervisior MCU/USB_A5")
			(pintype "passive")
		)
		(pad "34" smd rect
			(at 3.25 -1.975 270)
			(size 1.5 0.3)
			(layers "F.Cu" "F.Mask")
			(net 703 "+5V")
			(pintype "passive")
		)
		(pad "35" smd rect
			(at 3.75 1.976 270)
			(size 1.5 0.3)
			(layers "F.Cu" "F.Mask")
			(net 1064 "/Supervisior MCU/USB_A3")
			(pintype "passive")
		)
		(pad "36" smd rect
			(at 3.75 -1.975 270)
			(size 1.5 0.3)
			(layers "F.Cu" "F.Mask")
			(net 703 "+5V")
			(pintype "passive")
		)
		(pad "37" smd rect
			(at 4.25 1.976 270)
			(size 1.5 0.3)
			(layers "F.Cu" "F.Mask")
			(net 1101 "/Supervisior MCU/SDA0")
			(pintype "passive")
		)
		(pad "38" smd rect
			(at 4.25 -1.975 270)
			(size 1.5 0.3)
			(layers "F.Cu" "F.Mask")
			(net 703 "+5V")
			(pintype "passive")
		)
		(pad "39" smd rect
			(at 4.75 1.976 270)
			(size 1.5 0.3)
			(layers "F.Cu" "F.Mask")
			(net 1065 "/Supervisior MCU/USB_A4")
			(pintype "passive")
		)
		(pad "40" smd rect
			(at 4.75 -1.975 270)
			(size 1.5 0.3)
			(layers "F.Cu" "F.Mask")
			(net 703 "+5V")
			(pintype "passive")
		)
	)
)
